(kicad_pcb
	(version 20241229)
	(generator "pcbnew")
	(generator_version "9.0")
	(general
		(thickness 1.61)
		(legacy_teardrops no)
	)
	(paper "A3")
	(title_block
		(title "RDIMM DDR5 Tester")
		(date "2026-05-21")
		(rev "2.2.0")
		(company "Antmicro")
		(comment 9 "footprints 124-127 of 796")
	)
	(layers
		(0 "F.Cu" signal)
		(4 "In1.Cu" power)
		(6 "In2.Cu" mixed)
		(8 "In3.Cu" power)
		(10 "In4.Cu" mixed)
		(12 "In5.Cu" power)
		(14 "In6.Cu" mixed)
		(16 "In7.Cu" power)
		(18 "In8.Cu" power)
		(20 "In9.Cu" mixed)
		(22 "In10.Cu" power)
		(2 "B.Cu" signal)
		(9 "F.Adhes" user "F.Adhesive")
		(11 "B.Adhes" user "B.Adhesive")
		(13 "F.Paste" user)
		(15 "B.Paste" user)
		(5 "F.SilkS" user "F.Silkscreen")
		(7 "B.SilkS" user "B.Silkscreen")
		(1 "F.Mask" user)
		(3 "B.Mask" user)
		(17 "Dwgs.User" user "User.Drawings")
		(19 "Cmts.User" user "User.Comments")
		(21 "Eco1.User" user "User.Eco1")
		(23 "Eco2.User" user "User.Eco2")
		(25 "Edge.Cuts" user)
		(27 "Margin" user)
		(31 "F.CrtYd" user "F.Courtyard")
		(29 "B.CrtYd" user "B.Courtyard")
		(35 "F.Fab" user)
		(33 "B.Fab" user)
	)
	(footprint "antmicro-footprints:C_Pol_EIA-B"
		(layer "F.Cu")
		(at 207.290002 158.5 90)
		(property "Reference" "C25"
			(at 0 -2.3 90)
			(layer "F.SilkS")
			(effects
				(font
					(size 0.7 0.7)
					(thickness 0.15)
				)
				(justify left bottom)
			)
		)
		(property "Value" "C_Pol_330u_6.3V_KEMET-T520-B"
			(at 0 2.85 90)
			(layer "F.Fab")
			(effects
				(font
					(size 0.7 0.7)
					(thickness 0.15)
				)
				(justify left bottom)
			)
		)
		(property "Datasheet" "https://www.kemet.com/en/us/capacitors/product/T520B337M006ATE040.html"
			(at 0 0 90)
			(layer "F.Fab")
			(hide yes)
			(effects
				(font
					(size 1.27 1.27)
					(thickness 0.15)
				)
			)
		)
		(property "Val" "330u"
			(at 0 0 90)
			(unlocked yes)
			(layer "F.Fab")
			(hide yes)
			(effects
				(font
					(size 1 1)
					(thickness 0.15)
				)
			)
		)
		(property "MPN" "T520B337M006ATE040"
			(at 0 0 90)
			(unlocked yes)
			(layer "F.Fab")
			(hide yes)
			(effects
				(font
					(size 1 1)
					(thickness 0.15)
				)
			)
		)
		(property "Manufacturer" "KEMET"
			(at 0 0 90)
			(unlocked yes)
			(layer "F.Fab")
			(hide yes)
			(effects
				(font
					(size 1 1)
					(thickness 0.15)
				)
			)
		)
		(property "License" "Apache-2.0"
			(at 0 0 90)
			(unlocked yes)
			(layer "F.Fab")
			(hide yes)
			(effects
				(font
					(size 1 1)
					(thickness 0.15)
				)
			)
		)
		(property "Author" "Antmicro"
			(at 0 0 90)
			(unlocked yes)
			(layer "F.Fab")
			(hide yes)
			(effects
				(font
					(size 1 1)
					(thickness 0.15)
				)
			)
		)
		(property "Voltage" "6.3V"
			(at 0 0 90)
			(unlocked yes)
			(layer "F.Fab")
			(hide yes)
			(effects
				(font
					(size 1 1)
					(thickness 0.15)
				)
			)
		)
		(property "Dielectric" "template_dielectric"
			(at 0 0 90)
			(unlocked yes)
			(layer "F.Fab")
			(hide yes)
			(effects
				(font
					(size 1 1)
					(thickness 0.15)
				)
			)
		)
		(sheetname "/FPGA power/")
		(sheetfile "fpga-power.kicad_sch")
		(attr smd)
		(fp_line
			(start -2.521 -1.676)
			(end -2.123 -1.676)
			(stroke
				(width 0.15)
				(type solid)
			)
			(layer "F.SilkS")
		)
		(fp_line
			(start -1.8 -1.6)
			(end 1.8 -1.6)
			(stroke
				(width 0.15)
				(type solid)
			)
			(layer "F.SilkS")
		)
		(fp_line
			(start -2.325 -1.475)
			(end -2.325 -1.878)
			(stroke
				(width 0.15)
				(type solid)
			)
			(layer "F.SilkS")
		)
		(fp_line
			(start 1.8 -1.3)
			(end 1.8 -1.6)
			(stroke
				(width 0.15)
				(type solid)
			)
			(layer "F.SilkS")
		)
		(fp_line
			(start -1.8 -1.3)
			(end -1.8 -1.6)
			(stroke
				(width 0.15)
				(type solid)
			)
			(layer "F.SilkS")
		)
		(fp_line
			(start 1.8 1.3)
			(end 1.8 1.6)
			(stroke
				(width 0.15)
				(type solid)
			)
			(layer "F.SilkS")
		)
		(fp_line
			(start -1.8 1.3)
			(end -1.8 1.6)
			(stroke
				(width 0.15)
				(type solid)
			)
			(layer "F.SilkS")
		)
		(fp_line
			(start 1.8 1.6)
			(end -1.8 1.6)
			(stroke
				(width 0.15)
				(type solid)
			)
			(layer "F.SilkS")
		)
		(fp_line
			(start 1.959 -1.75)
			(end -1.97 -1.75)
			(stroke
				(width 0.05)
				(type solid)
			)
			(layer "F.CrtYd")
		)
		(fp_line
			(start 1.959 -1.75)
			(end 1.959 -1.35)
			(stroke
				(width 0.05)
				(type solid)
			)
			(layer "F.CrtYd")
		)
		(fp_line
			(start -1.97 -1.75)
			(end -1.97 -1.35)
			(stroke
				(width 0.05)
				(type solid)
			)
			(layer "F.CrtYd")
		)
		(fp_line
			(start 2.399 -1.35)
			(end 1.959 -1.35)
			(stroke
				(width 0.05)
				(type solid)
			)
			(layer "F.CrtYd")
		)
		(fp_line
			(start 2.399 -1.35)
			(end 2.4 1.35)
			(stroke
				(width 0.05)
				(type solid)
			)
			(layer "F.CrtYd")
		)
		(fp_line
			(start -1.97 -1.35)
			(end -2.41 -1.35)
			(stroke
				(width 0.05)
				(type solid)
			)
			(layer "F.CrtYd")
		)
		(fp_line
			(start -2.411 -1.35)
			(end -2.41 1.35)
			(stroke
				(width 0.05)
				(type solid)
			)
			(layer "F.CrtYd")
		)
		(fp_line
			(start 2.4 1.35)
			(end 1.96 1.35)
			(stroke
				(width 0.05)
				(type solid)
			)
			(layer "F.CrtYd")
		)
		(fp_line
			(start 1.96 1.35)
			(end 1.96 1.75)
			(stroke
				(width 0.05)
				(type solid)
			)
			(layer "F.CrtYd")
		)
		(fp_line
			(start -1.97 1.35)
			(end -2.41 1.35)
			(stroke
				(width 0.05)
				(type solid)
			)
			(layer "F.CrtYd")
		)
		(fp_line
			(start -1.97 1.35)
			(end -1.97 1.75)
			(stroke
				(width 0.05)
				(type solid)
			)
			(layer "F.CrtYd")
		)
		(fp_line
			(start 1.96 1.75)
			(end -1.97 1.75)
			(stroke
				(width 0.05)
				(type solid)
			)
			(layer "F.CrtYd")
		)
		(fp_line
			(start -1.7 1.324)
			(end -1.551 1.475)
			(stroke
				(width 0.15)
				(type solid)
			)
			(layer "F.Fab")
		)
		(fp_rect
			(start -1.72 -1.5)
			(end 1.719 1.499)
			(stroke
				(width 0.15)
				(type solid)
			)
			(fill no)
			(layer "F.Fab")
		)
		(fp_text user "Author: Antmicro"
			(at -2.665 6.85 90)
			(layer "F.Fab")
			(effects
				(font
					(size 0.7 0.7)
					(thickness 0.15)
				)
				(justify left bottom)
			)
		)
		(fp_text user "License: Apache-2.0"
			(at -2.665 5.65 90)
			(layer "F.Fab")
			(effects
				(font
					(size 0.7 0.7)
					(thickness 0.15)
				)
				(justify left bottom)
			)
		)
		(fp_text user "${REFERENCE}"
			(at -2.665 4.45 90)
			(layer "F.Fab")
			(effects
				(font
					(size 0.7 0.7)
					(thickness 0.15)
				)
				(justify left bottom)
			)
		)
		(pad "1" smd roundrect
			(at -1.551 0 90)
			(size 1.2 2.2)
			(layers "F.Cu" "F.Mask" "F.Paste")
			(roundrect_rratio 0.1)
			(net 553 "+0V85")
			(pintype "passive")
		)
		(pad "2" smd roundrect
			(at 1.55 0 90)
			(size 1.2 2.2)
			(layers "F.Cu" "F.Mask" "F.Paste")
			(roundrect_rratio 0.1)
			(net 1 "GND")
			(pintype "passive")
		)
	)
	(footprint "antmicro-footprints:SC70-3"
		(layer "F.Cu")
		(at 250.274499 137.899)
		(property "Reference" "Q17"
			(at 0.545501 1.111 90)
			(layer "F.SilkS")
			(effects
				(font
					(size 0.7 0.7)
					(thickness 0.15)
				)
				(justify left bottom)
			)
		)
		(property "Value" "BSS138PW"
			(at 0 2.3 0)
			(layer "F.Fab")
			(effects
				(font
					(size 0.7 0.7)
					(thickness 0.15)
				)
				(justify left bottom)
			)
		)
		(property "Datasheet" "https://assets.nexperia.com/documents/data-sheet/BSS138PW.pdf"
			(at 0 0 0)
			(layer "F.Fab")
			(hide yes)
			(effects
				(font
					(size 1.27 1.27)
					(thickness 0.15)
				)
			)
		)
		(property "MPN" "BSS138PW"
			(at 0 0 0)
			(unlocked yes)
			(layer "F.Fab")
			(hide yes)
			(effects
				(font
					(size 1 1)
					(thickness 0.15)
				)
			)
		)
		(property "Manufacturer" "Nexperia"
			(at 0 0 0)
			(unlocked yes)
			(layer "F.Fab")
			(hide yes)
			(effects
				(font
					(size 1 1)
					(thickness 0.15)
				)
			)
		)
		(property "Author" "Antmicro"
			(at 0 0 0)
			(unlocked yes)
			(layer "F.Fab")
			(hide yes)
			(effects
				(font
					(size 1 1)
					(thickness 0.15)
				)
			)
		)
		(property "License" "Apache-2.0"
			(at 0 0 0)
			(unlocked yes)
			(layer "F.Fab")
			(hide yes)
			(effects
				(font
					(size 1 1)
					(thickness 0.15)
				)
			)
		)
		(sheetname "/Supply/")
		(sheetfile "supply.kicad_sch")
		(attr smd)
		(fp_line
			(start -0.3 -1)
			(end 0.627 -0.999)
			(stroke
				(width 0.15)
				(type solid)
			)
			(layer "F.SilkS")
		)
		(fp_line
			(start -0.3 1)
			(end 0.627 1.001)
			(stroke
				(width 0.15)
				(type solid)
			)
			(layer "F.SilkS")
		)
		(fp_line
			(start 0.627 -0.6)
			(end 0.627 -0.999)
			(stroke
				(width 0.15)
				(type solid)
			)
			(layer "F.SilkS")
		)
		(fp_line
			(start 0.627 0.6)
			(end 0.627 1.001)
			(stroke
				(width 0.15)
				(type solid)
			)
			(layer "F.SilkS")
		)
		(fp_line
			(start -1.4 1)
			(end -1.4 -1)
			(stroke
				(width 0.05)
				(type solid)
			)
			(layer "F.CrtYd")
		)
		(fp_line
			(start -0.9 -1.3)
			(end -0.9 -1)
			(stroke
				(width 0.05)
				(type solid)
			)
			(layer "F.CrtYd")
		)
		(fp_line
			(start -0.9 -1.3)
			(end 0.9 -1.3)
			(stroke
				(width 0.05)
				(type solid)
			)
			(layer "F.CrtYd")
		)
		(fp_line
			(start -0.9 -1)
			(end -1.4 -1)
			(stroke
				(width 0.05)
				(type solid)
			)
			(layer "F.CrtYd")
		)
		(fp_line
			(start -0.9 1)
			(end -1.4 1)
			(stroke
				(width 0.05)
				(type solid)
			)
			(layer "F.CrtYd")
		)
		(fp_line
			(start -0.9 1.3)
			(end -0.9 1)
			(stroke
				(width 0.05)
				(type solid)
			)
			(layer "F.CrtYd")
		)
		(fp_line
			(start 0.9 -1.3)
			(end 0.9 -0.4)
			(stroke
				(width 0.05)
				(type solid)
			)
			(layer "F.CrtYd")
		)
		(fp_line
			(start 0.9 -0.4)
			(end 1.4 -0.4)
			(stroke
				(width 0.05)
				(type solid)
			)
			(layer "F.CrtYd")
		)
		(fp_line
			(start 0.9 0.4)
			(end 0.9 1.3)
			(stroke
				(width 0.05)
				(type solid)
			)
			(layer "F.CrtYd")
		)
		(fp_line
			(start 0.9 1.3)
			(end -0.9 1.3)
			(stroke
				(width 0.05)
				(type solid)
			)
			(layer "F.CrtYd")
		)
		(fp_line
			(start 1.4 -0.4)
			(end 1.4 0.4)
			(stroke
				(width 0.05)
				(type solid)
			)
			(layer "F.CrtYd")
		)
		(fp_line
			(start 1.4 0.4)
			(end 0.9 0.4)
			(stroke
				(width 0.05)
				(type solid)
			)
			(layer "F.CrtYd")
		)
		(fp_rect
			(start -0.623 -0.999)
			(end 0.627 1.001)
			(stroke
				(width 0.15)
				(type solid)
			)
			(fill no)
			(layer "F.Fab")
		)
		(fp_text user "Author: Antmicro"
			(at -1.45 5.782 0)
			(layer "F.Fab")
			(effects
				(font
					(size 0.7 0.7)
					(thickness 0.15)
				)
				(justify left bottom)
			)
		)
		(fp_text user "License: Apache-2.0"
			(at -1.45 6.782 0)
			(layer "F.Fab")
			(effects
				(font
					(size 0.7 0.7)
					(thickness 0.15)
				)
				(justify left bottom)
			)
		)
		(fp_text user "${REFERENCE}"
			(at -1.45 4.783 0)
			(layer "F.Fab")
			(effects
				(font
					(size 0.7 0.7)
					(thickness 0.15)
				)
				(justify left bottom)
			)
		)
		(pad "1" smd rect
			(at -1.051 -0.65 90)
			(size 0.6 0.6)
			(layers "F.Cu" "F.Mask" "F.Paste")
			(net 287 "Net-(Q17-G)")
			(pinfunction "G")
			(pintype "passive")
		)
		(pad "2" smd rect
			(at -1.051 0.65 90)
			(size 0.6 0.6)
			(layers "F.Cu" "F.Mask" "F.Paste")
			(net 1 "GND")
			(pinfunction "S")
			(pintype "passive")
		)
		(pad "3" smd rect
			(at 1.05 0 90)
			(size 0.6 0.6)
			(layers "F.Cu" "F.Mask" "F.Paste")
			(net 625 "Net-(Q17-D)")
			(pinfunction "D")
			(pintype "passive")
		)
	)
	(footprint "antmicro-footprints:C_0603_1608Metric"
		(layer "F.Cu")
		(at 257 177.9)
		(descr "Capacitor SMD 0603")
		(tags "capacitor 0603")
		(property "Reference" "C260"
			(at 1.25 0.2 0)
			(layer "F.SilkS")
			(effects
				(font
					(size 0.7 0.7)
					(thickness 0.15)
				)
				(justify left bottom)
			)
		)
		(property "Value" "C_22u_0603"
			(at -1.42757 1.770288 0)
			(layer "F.Fab")
			(effects
				(font
					(size 0.7 0.7)
					(thickness 0.15)
				)
				(justify left bottom)
			)
		)
		(property "Datasheet" "https://www.murata.com/products/productdetail?partno=GRM188R60J226MEA0%23"
			(at 0 0 0)
			(layer "F.Fab")
			(hide yes)
			(effects
				(font
					(size 1.27 1.27)
					(thickness 0.15)
				)
			)
		)
		(property "Manufacturer" "Murata"
			(at 0 0 0)
			(unlocked yes)
			(layer "F.Fab")
			(hide yes)
			(effects
				(font
					(size 1 1)
					(thickness 0.15)
				)
			)
		)
		(property "MPN" "GRM188R60J226MEA0D"
			(at 0 0 0)
			(unlocked yes)
			(layer "F.Fab")
			(hide yes)
			(effects
				(font
					(size 1 1)
					(thickness 0.15)
				)
			)
		)
		(property "Val" "22u"
			(at 0 0 0)
			(unlocked yes)
			(layer "F.Fab")
			(hide yes)
			(effects
				(font
					(size 1 1)
					(thickness 0.15)
				)
			)
		)
		(property "License" "Apache-2.0"
			(at 0 0 0)
			(unlocked yes)
			(layer "F.Fab")
			(hide yes)
			(effects
				(font
					(size 1 1)
					(thickness 0.15)
				)
			)
		)
		(property "Author" "Antmicro"
			(at 0 0 0)
			(unlocked yes)
			(layer "F.Fab")
			(hide yes)
			(effects
				(font
					(size 1 1)
					(thickness 0.15)
				)
			)
		)
		(property "Voltage" ""
			(at 0 0 0)
			(unlocked yes)
			(layer "F.Fab")
			(hide yes)
			(effects
				(font
					(size 1 1)
					(thickness 0.15)
				)
			)
		)
		(property "Dielectric" ""
			(at 0 0 0)
			(unlocked yes)
			(layer "F.Fab")
			(hide yes)
			(effects
				(font
					(size 1 1)
					(thickness 0.15)
				)
			)
		)
		(sheetname "/Supply/DC-DC AUX, MGT/")
		(sheetfile "dc-dc-aux-mgt.kicad_sch")
		(attr smd)
		(fp_line
			(start -0.15 -0.4)
			(end 0.15 -0.4)
			(stroke
				(width 0.15)
				(type solid)
			)
			(layer "F.SilkS")
		)
		(fp_line
			(start -0.15 0.4)
			(end 0.15 0.4)
			(stroke
				(width 0.15)
				(type solid)
			)
			(layer "F.SilkS")
		)
		(fp_rect
			(start -1.25 -0.65)
			(end 1.25 0.65)
			(stroke
				(width 0.05)
				(type solid)
			)
			(fill no)
			(layer "F.CrtYd")
		)
		(fp_rect
			(start -0.8 -0.4)
			(end 0.8 0.4)
			(stroke
				(width 0.15)
				(type solid)
			)
			(fill no)
			(layer "F.Fab")
		)
		(fp_text user "Author: Antmicro"
			(at -1.682 4.894 0)
			(layer "F.Fab")
			(effects
				(font
					(size 0.7 0.7)
					(thickness 0.15)
				)
				(justify left bottom)
			)
		)
		(fp_text user "License: Apache-2.0"
			(at -1.682 5.895 0)
			(layer "F.Fab")
			(effects
				(font
					(size 0.7 0.7)
					(thickness 0.15)
				)
				(justify left bottom)
			)
		)
		(fp_text user "${REFERENCE}"
			(at -1.682 3.895 0)
			(layer "F.Fab")
			(effects
				(font
					(size 0.7 0.7)
					(thickness 0.15)
				)
				(justify left bottom)
			)
		)
		(pad "1" smd roundrect
			(at -0.7 0)
			(size 0.8 1)
			(layers "F.Cu" "F.Mask" "F.Paste")
			(roundrect_rratio 0.2)
			(net 1 "GND")
			(pintype "passive")
		)
		(pad "2" smd roundrect
			(at 0.7 0)
			(size 0.8 1)
			(layers "F.Cu" "F.Mask" "F.Paste")
			(roundrect_rratio 0.2)
			(net 225 "/Supply/DC-DC AUX, MGT/MGTAVCCAUX_local")
			(pintype "passive")
		)
	)
	(footprint "antmicro-footprints:VSSOP-8_2.3x2mm_P0.5mm"
		(layer "F.Cu")
		(at 239.274499 186.499)
		(property "Reference" "U23"
			(at -1.15 2.1 0)
			(layer "F.SilkS")
			(effects
				(font
					(size 0.7 0.7)
					(thickness 0.15)
				)
				(justify left bottom)
			)
		)
		(property "Value" "TS5A3359_VSSOP"
			(at 0 2.258 0)
			(layer "F.Fab")
			(effects
				(font
					(size 0.7 0.7)
					(thickness 0.15)
				)
				(justify left bottom)
			)
		)
		(property "Datasheet" "https://www.ti.com/general/docs/suppproductinfo.tsp?distId=26&gotoUrl=http%3A%2F%2Fwww.ti.com%2Flit%2Fgpn%2Fts5a3359"
			(at 0 0 0)
			(layer "F.Fab")
			(hide yes)
			(effects
				(font
					(size 1.27 1.27)
					(thickness 0.15)
				)
			)
		)
		(property "MPN" "TS5A3359DCUR"
			(at 0 0 0)
			(unlocked yes)
			(layer "F.Fab")
			(hide yes)
			(effects
				(font
					(size 1 1)
					(thickness 0.15)
				)
			)
		)
		(property "Manufacturer" "Texas Instruments"
			(at 0 0 0)
			(unlocked yes)
			(layer "F.Fab")
			(hide yes)
			(effects
				(font
					(size 1 1)
					(thickness 0.15)
				)
			)
		)
		(property "Author" "Antmicro"
			(at 0 0 0)
			(unlocked yes)
			(layer "F.Fab")
			(hide yes)
			(effects
				(font
					(size 1 1)
					(thickness 0.15)
				)
			)
		)
		(property "License" "Apache-2.0"
			(at 0 0 0)
			(unlocked yes)
			(layer "F.Fab")
			(hide yes)
			(effects
				(font
					(size 1 1)
					(thickness 0.15)
				)
			)
		)
		(sheetname "/I^{2}C + I3C/")
		(sheetfile "i2c.kicad_sch")
		(attr smd)
		(fp_line
			(start -0.82 -0.992)
			(end 0.825 -0.992)
			(stroke
				(width 0.15)
				(type solid)
			)
			(layer "F.SilkS")
		)
		(fp_line
			(start 0.825 1.007)
			(end -0.82 1.007)
			(stroke
				(width 0.15)
				(type solid)
			)
			(layer "F.SilkS")
		)
		(fp_circle
			(center -1.402 -1.192)
			(end -1.352 -1.192)
			(stroke
				(width 0.15)
				(type solid)
			)
			(fill yes)
			(layer "F.SilkS")
		)
		(fp_rect
			(start 1.8 1.35)
			(end -1.8 -1.35)
			(stroke
				(width 0.05)
				(type solid)
			)
			(fill no)
			(layer "F.CrtYd")
		)
		(fp_line
			(start -0.7 -0.99)
			(end -1.14 -0.55)
			(stroke
				(width 0.15)
				(type solid)
			)
			(layer "F.Fab")
		)
		(fp_rect
			(start -1.147 -0.992)
			(end 1.151 1.007)
			(stroke
				(width 0.15)
				(type solid)
			)
			(fill no)
			(layer "F.Fab")
		)
		(fp_text user "License: Apache-2.0"
			(at -1.8 6.408 0)
			(layer "F.Fab")
			(effects
				(font
					(size 0.7 0.7)
					(thickness 0.15)
				)
				(justify left bottom)
			)
		)
		(fp_text user "Author: Antmicro"
			(at -1.8 5.208 0)
			(layer "F.Fab")
			(effects
				(font
					(size 0.7 0.7)
					(thickness 0.15)
				)
				(justify left bottom)
			)
		)
		(fp_text user "${REFERENCE}"
			(at -1.8 4.006 0)
			(layer "F.Fab")
			(effects
				(font
					(size 0.7 0.7)
					(thickness 0.15)
				)
				(justify left bottom)
			)
		)
		(pad "1" smd rect
			(at -1.372 -0.742)
			(size 0.75 0.4)
			(layers "F.Cu" "F.Mask" "F.Paste")
			(net 472 "/FPGA banks HD/FPGA_DDR.SDA")
			(pinfunction "NO1")
			(pintype "passive")
		)
		(pad "2" smd rect
			(at -1.372 -0.244)
			(size 0.75 0.3)
			(layers "F.Cu" "F.Mask" "F.Paste")
			(net 746 "/FPGA Config/FPGA_PWR.SDA")
			(pinfunction "NO2")
			(pintype "passive")
		)
		(pad "3" smd rect
			(at -1.372 0.256)
			(size 0.75 0.3)
			(layers "F.Cu" "F.Mask" "F.Paste")
			(net 527 "/Debug FTDI + VNA/FTDI.SDA")
			(pinfunction "NO3")
			(pintype "passive")
		)
		(pad "4" smd rect
			(at -1.372 0.757)
			(size 0.75 0.4)
			(layers "F.Cu" "F.Mask" "F.Paste")
			(net 1 "GND")
			(pinfunction "GND")
			(pintype "passive")
		)
		(pad "5" smd rect
			(at 1.377 0.757)
			(size 0.75 0.4)
			(layers "F.Cu" "F.Mask" "F.Paste")
			(net 405 "IN2")
			(pinfunction "IN2")
			(pintype "passive")
		)
		(pad "6" smd rect
			(at 1.377 0.256)
			(size 0.75 0.3)
			(layers "F.Cu" "F.Mask" "F.Paste")
			(net 404 "IN1")
			(pinfunction "IN1")
			(pintype "passive")
		)
		(pad "7" smd rect
			(at 1.377 -0.244)
			(size 0.75 0.3)
			(layers "F.Cu" "F.Mask" "F.Paste")
			(net 533 "/I^{2}C + I3C/PWR.SDA")
			(pinfunction "COM")
			(pintype "passive")
		)
		(pad "8" smd rect
			(at 1.377 -0.742)
			(size 0.75 0.4)
			(layers "F.Cu" "F.Mask" "F.Paste")
			(net 38 "+3V3_AON")
			(pinfunction "VCC")
			(pintype "passive")
		)
	)
)
